# TIMECARD (Time Appliance Project (Time Card)) — schematic netlist excerpt (pin names and nets, part order shuffled) for the footprints in the layout excerpt that follows; sources: Cadence DE-HDL packaged netlist, KiCad conversion of R4006-B0001-02_R01.brd

C212  CAPACITOR  0.1UF 10V 10%  pkg SMC_0402R_H022  page 14 : \1\ = XP1R8V_FPGA_VCCAUX ; \2\ = SG
R430  RESISTOR  33OHM 1%  pkg SMC_0402R_H016  page 25 : \1\ = FPGA_IO_4 ; \2\ = UNNAMED_16_CONNHDR2X6FSSMT_I161

(kicad_pcb
	(version 20260206)
	(generator "pcbnew")
	(generator_version "10.0")
	(general
		(thickness 1.6)
		(legacy_teardrops no)
	)
	(paper "A4")
	(title_block
		(title "timecard-production-celestica-r4006 — R4006-B0001-02_R01.brd")
		(comment 1 "Time Appliance Project (Time Card) / footprints 827-828 of 1113")
	)
	(layers
		(0 "F.Cu" signal "TOP")
		(4 "In1.Cu" signal "L02_GND1")
		(6 "In2.Cu" signal "L03_SIG1")
		(8 "In3.Cu" signal "L04_GND2")
		(10 "In4.Cu" signal "L05_VCC1")
		(12 "In5.Cu" signal "L06_VCC2")
		(14 "In6.Cu" signal "L07_GND3")
		(16 "In7.Cu" signal "L08_SIG2")
		(18 "In8.Cu" signal "L09_GND4")
		(2 "B.Cu" signal "BOTTOM")
		(9 "F.Adhes" user "F.Adhesive")
		(11 "B.Adhes" user "B.Adhesive")
		(13 "F.Paste" user "Package Geometry/Pastemask Top")
		(15 "B.Paste" user "Package Geometry/Pastemask Bottom")
		(5 "F.SilkS" user "Ref Des/Silkscreen Top")
		(7 "B.SilkS" user "Ref Des/Silkscreen Bottom")
		(1 "F.Mask" user "Board Geometry/Soldermask Top")
		(3 "B.Mask" user "Board Geometry/Soldermask Bottom")
		(17 "Dwgs.User" user "User.Drawings")
		(19 "Cmts.User" user "User.Comments")
		(21 "Eco1.User" user "User.Eco1")
		(23 "Eco2.User" user "User.Eco2")
		(25 "Edge.Cuts" user "Board Geometry/Outline")
		(27 "Margin" user)
		(31 "F.CrtYd" user "Package Geometry/Place Bound Top")
		(29 "B.CrtYd" user "Package Geometry/Place Bound Bottom")
		(35 "F.Fab" user "Ref Des/Assembly Top")
		(33 "B.Fab" user "Ref Des/Assembly Bottom")
	)
	(footprint ""
		(layer "B.Cu")
		(at 156.337 -45.466 90)
		(property "Reference" "R430"
			(at -10.70737 -0.254 0)
			(unlocked yes)
			(layer "B.SilkS")
			(effects
				(font
					(size 0.7874 0.5842)
					(thickness 0.1524)
				)
				(justify mirror)
			)
		)
		(property "Value" "VAL*"
			(at -0.02032 2.13233 90)
			(unlocked yes)
			(layer "B.Fab")
			(hide yes)
			(effects
				(font
					(size 0.7874 0.5842)
					(thickness 0.1524)
				)
				(justify mirror)
			)
		)
		(property "Tolerance" "TOL*"
			(at -0.044704 3.05435 90)
			(unlocked yes)
			(layer "Cmts.User")
			(hide yes)
			(effects
				(font
					(size 0.7874 0.5842)
					(thickness 0.1524)
				)
				(justify mirror)
			)
		)
		(property "User Part Number" "PARTNUM*"
			(at -0.02032 4.024884 90)
			(unlocked yes)
			(layer "Cmts.User")
			(hide yes)
			(effects
				(font
					(size 0.7874 0.5842)
					(thickness 0.1524)
				)
				(justify mirror)
			)
		)
		(property "Device Type" "RESISTOR-G155-133R0-01,33OHM,1%"
			(at -0.008382 1.210564 90)
			(unlocked yes)
			(layer "B.Fab")
			(hide yes)
			(effects
				(font
					(size 0.7874 0.5842)
					(thickness 0.1524)
				)
				(justify mirror)
			)
		)
		(duplicate_pad_numbers_are_jumpers no)
		(fp_line
			(start 1.143 -0.5588)
			(end 1.143 0.5588)
			(stroke
				(width 0.1)
				(type default)
			)
			(layer "B.SilkS")
		)
		(fp_line
			(start -1.143 -0.5588)
			(end 1.143 -0.5588)
			(stroke
				(width 0.1)
				(type default)
			)
			(layer "B.SilkS")
		)
		(fp_line
			(start 1.143 0.5588)
			(end -1.143 0.5588)
			(stroke
				(width 0.1)
				(type default)
			)
			(layer "B.SilkS")
		)
		(fp_line
			(start -1.143 0.5588)
			(end -1.143 -0.5588)
			(stroke
				(width 0.1)
				(type default)
			)
			(layer "B.SilkS")
		)
		(fp_poly
			(pts
				(xy 1.143 0.5588) (xy -1.143 0.5588) (xy -1.143 -0.5588) (xy 1.143 -0.5588)
			)
			(stroke
				(width 0)
				(type default)
			)
			(fill no)
			(layer "B.CrtYd")
		)
		(fp_line
			(start 0.508 -0.3048)
			(end 0.508 0.3048)
			(stroke
				(width 0.1)
				(type default)
			)
			(layer "B.Fab")
		)
		(fp_line
			(start -0.508 -0.3048)
			(end 0.508 -0.3048)
			(stroke
				(width 0.1)
				(type default)
			)
			(layer "B.Fab")
		)
		(fp_line
			(start 0.508 0.3048)
			(end -0.508 0.3048)
			(stroke
				(width 0.1)
				(type default)
			)
			(layer "B.Fab")
		)
		(fp_line
			(start -0.508 0.3048)
			(end -0.508 -0.3048)
			(stroke
				(width 0.1)
				(type default)
			)
			(layer "B.Fab")
		)
		(pad "1" smd rect
			(at 0.5334 0 270)
			(size 0.7112 0.6096)
			(layers "B.Cu" "B.Mask" "B.Paste")
			(net "FPGA_IO_4")
		)
		(pad "2" smd rect
			(at -0.5334 0 270)
			(size 0.7112 0.6096)
			(layers "B.Cu" "B.Mask" "B.Paste")
			(net "UNNAMED_16_CONNHDR2X6FSSMT_I161")
		)
		(zone
			(layer "B.Cu")
			(hatch none 0.5)
			(connect_pads
				(clearance 0)
			)
			(min_thickness 0.25)
			(keepout
				(tracks not_allowed)
				(vias allowed)
				(pads allowed)
				(copperpour not_allowed)
				(footprints allowed)
			)
			(placement
				(enabled no)
				(sheetname "")
			)
			(fill
				(thermal_gap 0.5)
				(thermal_bridge_width 0.5)
				(island_removal_mode 0)
			)
			(polygon
				(pts
					(xy 156.6418 -45.5422) (xy 156.0322 -45.5422) (xy 156.0322 -45.3898) (xy 156.6418 -45.3898)
				)
			)
		)
		(zone
			(layer "B.Cu")
			(hatch none 0.5)
			(connect_pads
				(clearance 0)
			)
			(min_thickness 0.25)
			(keepout
				(tracks allowed)
				(vias not_allowed)
				(pads allowed)
				(copperpour not_allowed)
				(footprints allowed)
			)
			(placement
				(enabled no)
				(sheetname "")
			)
			(fill
				(thermal_gap 0.5)
				(thermal_bridge_width 0.5)
				(island_removal_mode 0)
			)
			(polygon
				(pts
					(xy 156.6418 -45.5422) (xy 156.0322 -45.5422) (xy 156.0322 -45.3898) (xy 156.6418 -45.3898)
				)
			)
		)
	)
	(footprint ""
		(layer "B.Cu")
		(at 110.3376 -44.2214)
		(property "Reference" "C212"
			(at -43.4086 1.45415 0)
			(unlocked yes)
			(layer "B.SilkS")
			(effects
				(font
					(size 0.635 0.4064)
					(thickness 0.1524)
				)
				(justify mirror)
			)
		)
		(property "Value" "VAL*"
			(at -0.0762 2.067306 0)
			(unlocked yes)
			(layer "B.Fab")
			(hide yes)
			(effects
				(font
					(size 0.7874 0.5842)
					(thickness 0.1524)
				)
				(justify mirror)
			)
		)
		(property "Device Type" "CAPACITOR-G105-0B104-CK,0.1UF,A"
			(at -0.0508 1.127506 0)
			(unlocked yes)
			(layer "B.Fab")
			(hide yes)
			(effects
				(font
					(size 0.7874 0.5842)
					(thickness 0.1524)
				)
				(justify mirror)
			)
		)
		(property "User Part Number" "PARTNUM*"
			(at -0.1016 4.023106 0)
			(unlocked yes)
			(layer "Cmts.User")
			(hide yes)
			(effects
				(font
					(size 0.7874 0.5842)
					(thickness 0.1524)
				)
				(justify mirror)
			)
		)
		(property "Tolerance" "TOL*"
			(at -0.0762 3.032506 0)
			(unlocked yes)
			(layer "Cmts.User")
			(hide yes)
			(effects
				(font
					(size 0.7874 0.5842)
					(thickness 0.1524)
				)
				(justify mirror)
			)
		)
		(duplicate_pad_numbers_are_jumpers no)
		(fp_line
			(start -1.143 -0.5588)
			(end 1.143 -0.5588)
			(stroke
				(width 0.1)
				(type default)
			)
			(layer "B.SilkS")
		)
		(fp_line
			(start -1.143 0.5588)
			(end -1.143 -0.5588)
			(stroke
				(width 0.1)
				(type default)
			)
			(layer "B.SilkS")
		)
		(fp_line
			(start 1.143 -0.5588)
			(end 1.143 0.5588)
			(stroke
				(width 0.1)
				(type default)
			)
			(layer "B.SilkS")
		)
		(fp_line
			(start 1.143 0.5588)
			(end -1.143 0.5588)
			(stroke
				(width 0.1)
				(type default)
			)
			(layer "B.SilkS")
		)
		(fp_poly
			(pts
				(xy 1.143 0.5588) (xy -1.143 0.5588) (xy -1.143 -0.5588) (xy 1.143 -0.5588)
			)
			(stroke
				(width 0)
				(type default)
			)
			(fill no)
			(layer "B.CrtYd")
		)
		(fp_line
			(start -0.508 -0.3048)
			(end 0.508 -0.3048)
			(stroke
				(width 0.1)
				(type default)
			)
			(layer "B.Fab")
		)
		(fp_line
			(start -0.508 0.3048)
			(end -0.508 -0.3048)
			(stroke
				(width 0.1)
				(type default)
			)
			(layer "B.Fab")
		)
		(fp_line
			(start 0.508 -0.3048)
			(end 0.508 0.3048)
			(stroke
				(width 0.1)
				(type default)
			)
			(layer "B.Fab")
		)
		(fp_line
			(start 0.508 0.3048)
			(end -0.508 0.3048)
			(stroke
				(width 0.1)
				(type default)
			)
			(layer "B.Fab")
		)
		(pad "1" smd rect
			(at 0.5334 0 180)
			(size 0.7112 0.6096)
			(layers "B.Cu" "B.Mask" "B.Paste")
			(net "XP1R8V_FPGA_VCCAUX")
		)
		(pad "2" smd rect
			(at -0.5334 0 180)
			(size 0.7112 0.6096)
			(layers "B.Cu" "B.Mask" "B.Paste")
			(net "SG")
		)
		(zone
			(layer "B.Cu")
			(hatch none 0.5)
			(connect_pads
				(clearance 0)
			)
			(min_thickness 0.25)
			(keepout
				(tracks not_allowed)
				(vias allowed)
				(pads allowed)
				(copperpour not_allowed)
				(footprints allowed)
			)
			(placement
				(enabled no)
				(sheetname "")
			)
			(fill
				(thermal_gap 0.5)
				(thermal_bridge_width 0.5)
				(island_removal_mode 0)
			)
			(polygon
				(pts
					(xy 110.4138 -43.9166) (xy 110.4138 -44.5262) (xy 110.2614 -44.5262) (xy 110.2614 -43.9166)
				)
			)
		)
		(zone
			(layer "B.Cu")
			(hatch none 0.5)
			(connect_pads
				(clearance 0)
			)
			(min_thickness 0.25)
			(keepout
				(tracks allowed)
				(vias not_allowed)
				(pads allowed)
				(copperpour not_allowed)
				(footprints allowed)
			)
			(placement
				(enabled no)
				(sheetname "")
			)
			(fill
				(thermal_gap 0.5)
				(thermal_bridge_width 0.5)
				(island_removal_mode 0)
			)
			(polygon
				(pts
					(xy 110.4138 -43.9166) (xy 110.4138 -44.5262) (xy 110.2614 -44.5262) (xy 110.2614 -43.9166)
				)
			)
		)
	)
)
